(kicad_pcb
	(version 20260206)
	(generator "pcbnew")
	(generator_version "10.0")
	(general
		(thickness 1.6)
		(legacy_teardrops no)
	)
	(paper "A4")
	(title_block
		(title "v1-tray-backplane — T6M_tray_BP_c_1023_1120.brd")
		(comment 1 "Open CloudServer (Microsoft) / footprints 20-26 of 170")
	)
	(layers
		(0 "F.Cu" signal "TOP")
		(4 "In1.Cu" signal "GND")
		(6 "In2.Cu" signal "IN1")
		(8 "In3.Cu" signal "VCC")
		(10 "In4.Cu" signal "VCC1")
		(12 "In5.Cu" signal "IN2")
		(14 "In6.Cu" signal "GND1")
		(2 "B.Cu" signal "BOTTOM")
		(9 "F.Adhes" user "F.Adhesive")
		(11 "B.Adhes" user "B.Adhesive")
		(13 "F.Paste" user "Package Geometry/Pastemask Top")
		(15 "B.Paste" user "Package Geometry/Pastemask Bottom")
		(5 "F.SilkS" user "Ref Des/Silkscreen Top")
		(7 "B.SilkS" user "Ref Des/Silkscreen Bottom")
		(1 "F.Mask" user "Board Geometry/Soldermask Top")
		(3 "B.Mask" user "Board Geometry/Soldermask Bottom")
		(17 "Dwgs.User" user "User.Drawings")
		(19 "Cmts.User" user "User.Comments")
		(21 "Eco1.User" user "User.Eco1")
		(23 "Eco2.User" user "User.Eco2")
		(25 "Edge.Cuts" user "Board Geometry/Outline")
		(27 "Margin" user)
		(31 "F.CrtYd" user "Package Geometry/Place Bound Top")
		(29 "B.CrtYd" user "Package Geometry/Place Bound Bottom")
		(35 "F.Fab" user "Ref Des/Assembly Top")
		(33 "B.Fab" user "Ref Des/Assembly Bottom")
	)
	(footprint ""
		(layer "F.Cu")
		(at 142.49019 -14.390116 180)
		(property "Reference" "U5"
			(at 2.73558 -10.552684 0)
			(unlocked yes)
			(layer "F.SilkS")
			(effects
				(font
					(size 0.7874 0.5842)
					(thickness 0.1524)
				)
				(justify left)
			)
		)
		(property "Value" ""
			(at 0 0 180)
			(layer "F.Fab")
			(effects
				(font
					(size 1.27 1.27)
				)
			)
		)
		(duplicate_pad_numbers_are_jumpers no)
		(fp_line
			(start 5.500116 3.700018)
			(end 4.191 3.700018)
			(stroke
				(width 0.1524)
				(type default)
			)
			(layer "F.SilkS")
		)
		(fp_line
			(start 5.500116 0.889)
			(end 5.500116 3.700018)
			(stroke
				(width 0.1524)
				(type default)
			)
			(layer "F.SilkS")
		)
		(fp_line
			(start 5.500116 -3.700018)
			(end 5.500116 -0.889)
			(stroke
				(width 0.1524)
				(type default)
			)
			(layer "F.SilkS")
		)
		(fp_line
			(start 3.7846 -3.700018)
			(end 5.500116 -3.700018)
			(stroke
				(width 0.1524)
				(type default)
			)
			(layer "F.SilkS")
		)
		(fp_line
			(start -3.7846 3.700018)
			(end -5.500116 3.700018)
			(stroke
				(width 0.1524)
				(type default)
			)
			(layer "F.SilkS")
		)
		(fp_line
			(start -5.500116 0.635)
			(end -5.500116 3.700018)
			(stroke
				(width 0.1524)
				(type default)
			)
			(layer "F.SilkS")
		)
		(fp_line
			(start -5.500116 -3.700018)
			(end -4.191 -3.700018)
			(stroke
				(width 0.1524)
				(type default)
			)
			(layer "F.SilkS")
		)
		(fp_line
			(start -5.500116 -3.700018)
			(end -5.500116 -0.635)
			(stroke
				(width 0.1524)
				(type default)
			)
			(layer "F.SilkS")
		)
		(fp_poly
			(pts
				(xy -3.387344 5.3848) (xy -3.946144 6.8072) (xy -2.853944 6.8072)
			)
			(stroke
				(width 0)
				(type default)
			)
			(fill yes)
			(layer "F.SilkS")
		)
		(fp_poly
			(pts
				(arc
					(start -4.064 -0.3302)
					(mid -4.8006 -1.0668)
					(end -5.5372 -0.3302)
				)
				(arc
					(start -5.5372 0.3048)
					(mid -5.314015 0.843615)
					(end -4.7752 1.0668)
				)
				(arc
					(start -4.7752 1.0668)
					(mid -4.272306 0.858494)
					(end -4.064 0.3556)
				)
			)
			(stroke
				(width 0)
				(type default)
			)
			(fill no)
			(layer "B.CrtYd")
		)
		(fp_poly
			(pts
				(arc
					(start 3.7338 0)
					(mid 5.8674 0)
					(end 3.7338 0)
				)
			)
			(stroke
				(width 0)
				(type default)
			)
			(fill no)
			(layer "B.CrtYd")
		)
		(fp_rect
			(start -5.5118 5.1308)
			(end 5.5118 -5.1308)
			(stroke
				(width 0)
				(type default)
			)
			(fill no)
			(layer "F.CrtYd")
		)
		(fp_text user "10"
			(at 4.718304 5.233924 90)
			(unlocked yes)
			(layer "F.SilkS")
			(effects
				(font
					(size 0.7874 0.5842)
					(thickness 0.1524)
				)
				(justify left)
			)
		)
		(fp_text user "11"
			(at 3.219704 -6.399276 90)
			(unlocked yes)
			(layer "F.SilkS")
			(effects
				(font
					(size 0.7874 0.5842)
					(thickness 0.1524)
				)
				(justify left)
			)
		)
		(fp_text user "1"
			(at -3.797046 5.749798 0)
			(unlocked yes)
			(layer "F.SilkS")
			(effects
				(font
					(size 0.7874 0.5842)
					(thickness 0.1524)
				)
				(justify left)
			)
		)
		(fp_text user "20"
			(at -4.578096 -8.583676 90)
			(unlocked yes)
			(layer "F.SilkS")
			(effects
				(font
					(size 0.7874 0.5842)
					(thickness 0.1524)
				)
				(justify left)
			)
		)
		(pad "" np_thru_hole oval
			(at -4.800092 0 180)
			(size 0.9652 1.6002)
			(drill oval 0.9652 1.6002)
			(layers "*.Cu" "*.Mask")
			(clearance 0.381)
			(thermal_gap 0.381)
		)
		(pad "" np_thru_hole circle
			(at 4.800092 0 180)
			(size 1.6002 1.6002)
			(drill 1.6002)
			(layers "*.Cu" "*.Mask")
			(clearance 0.381)
			(thermal_gap 0.381)
		)
		(pad "1" smd oval
			(at -3.400044 4.100068 180)
			(size 0.508 2.032)
			(layers "F.Cu" "F.Mask" "F.Paste")
			(net "GND")
		)
		(pad "2" smd oval
			(at -2.599944 4.100068 180)
			(size 0.508 2.032)
			(layers "F.Cu" "F.Mask" "F.Paste")
			(net "ENET10G_1_TX_FAULT")
		)
		(pad "3" smd oval
			(at -1.800098 4.100068 180)
			(size 0.508 2.032)
			(layers "F.Cu" "F.Mask" "F.Paste")
			(net "ENET10G_1_TX_DIS")
		)
		(pad "4" smd oval
			(at -0.999998 4.100068 180)
			(size 0.508 2.032)
			(layers "F.Cu" "F.Mask" "F.Paste")
			(net "ENET10G_1_SDA")
		)
		(pad "5" smd oval
			(at -0.199898 4.100068 180)
			(size 0.508 2.032)
			(layers "F.Cu" "F.Mask" "F.Paste")
			(net "ENET10G_1_SCL")
		)
		(pad "6" smd oval
			(at 0.599948 4.100068 180)
			(size 0.508 2.032)
			(layers "F.Cu" "F.Mask" "F.Paste")
			(net "ENET10G_1_MOD_DEF0")
		)
		(pad "7" smd oval
			(at 1.400048 4.100068 180)
			(size 0.508 2.032)
			(layers "F.Cu" "F.Mask" "F.Paste")
			(net "ENET10G_1_RS0")
		)
		(pad "8" smd oval
			(at 2.199894 4.100068 180)
			(size 0.508 2.032)
			(layers "F.Cu" "F.Mask" "F.Paste")
			(net "ENET10G_1_LOS")
		)
		(pad "9" smd oval
			(at 2.999994 4.100068 180)
			(size 0.508 2.032)
			(layers "F.Cu" "F.Mask" "F.Paste")
			(net "ENET10G_1_RS1")
		)
		(pad "10" smd oval
			(at 3.800094 4.100068 180)
			(size 0.508 2.032)
			(layers "F.Cu" "F.Mask" "F.Paste")
			(net "GND")
		)
		(pad "11" smd oval
			(at 3.400044 -4.100068 180)
			(size 0.508 2.032)
			(layers "F.Cu" "F.Mask" "F.Paste")
			(net "GND")
		)
		(pad "12" smd oval
			(at 2.599944 -4.100068 180)
			(size 0.508 2.032)
			(layers "F.Cu" "F.Mask" "F.Paste")
			(net "ENET10G_1_RDN")
		)
		(pad "13" smd oval
			(at 1.800098 -4.100068 180)
			(size 0.508 2.032)
			(layers "F.Cu" "F.Mask" "F.Paste")
			(net "ENET10G_1_RDP")
		)
		(pad "14" smd oval
			(at 0.999998 -4.100068 180)
			(size 0.508 2.032)
			(layers "F.Cu" "F.Mask" "F.Paste")
			(net "GND")
		)
		(pad "15" smd oval
			(at 0.199898 -4.100068 180)
			(size 0.508 2.032)
			(layers "F.Cu" "F.Mask" "F.Paste")
			(net "P3V3_10G_1_VCCR")
		)
		(pad "16" smd oval
			(at -0.599948 -4.100068 180)
			(size 0.508 2.032)
			(layers "F.Cu" "F.Mask" "F.Paste")
			(net "P3V3_10G_1_VCCT")
		)
		(pad "17" smd oval
			(at -1.400048 -4.100068 180)
			(size 0.508 2.032)
			(layers "F.Cu" "F.Mask" "F.Paste")
			(net "GND")
		)
		(pad "18" smd oval
			(at -2.199894 -4.100068 180)
			(size 0.508 2.032)
			(layers "F.Cu" "F.Mask" "F.Paste")
			(net "ENET10G_1_TDP")
		)
		(pad "19" smd oval
			(at -2.999994 -4.100068 180)
			(size 0.508 2.032)
			(layers "F.Cu" "F.Mask" "F.Paste")
			(net "ENET10G_1_TDN")
		)
		(pad "20" smd oval
			(at -3.800094 -4.100068 180)
			(size 0.508 2.032)
			(layers "F.Cu" "F.Mask" "F.Paste")
			(net "GND")
		)
		(zone
			(layers "F.Cu" "B.Cu" "In1.Cu" "In2.Cu" "In3.Cu" "In4.Cu" "In5.Cu" "In6.Cu")
			(hatch none 0.5)
			(connect_pads
				(clearance 0)
			)
			(min_thickness 0.25)
			(keepout
				(tracks not_allowed)
				(vias allowed)
				(pads allowed)
				(copperpour not_allowed)
				(footprints allowed)
			)
			(placement
				(enabled no)
				(sheetname "")
			)
			(fill
				(thermal_gap 0.5)
				(thermal_bridge_width 0.5)
				(island_removal_mode 0)
			)
			(polygon
				(pts
					(arc
						(start 147.26539 -15.609316)
						(mid 147.911968 -15.341494)
						(end 148.17979 -14.694916)
					)
					(arc
						(start 148.17979 -14.059916)
						(mid 147.29079 -13.170916)
						(end 146.40179 -14.059916)
					)
					(arc
						(start 146.40179 -14.745716)
						(mid 146.654733 -15.356373)
						(end 147.26539 -15.609316)
					)
				)
			)
		)
		(zone
			(layers "F.Cu" "B.Cu" "In1.Cu" "In2.Cu" "In3.Cu" "In4.Cu" "In5.Cu" "In6.Cu")
			(hatch none 0.5)
			(connect_pads
				(clearance 0)
			)
			(min_thickness 0.25)
			(keepout
				(tracks not_allowed)
				(vias allowed)
				(pads allowed)
				(copperpour not_allowed)
				(footprints allowed)
			)
			(placement
				(enabled no)
				(sheetname "")
			)
			(fill
				(thermal_gap 0.5)
				(thermal_bridge_width 0.5)
				(island_removal_mode 0)
			)
			(polygon
				(pts
					(arc
						(start 138.90879 -14.390116)
						(mid 136.47039 -14.390116)
						(end 138.90879 -14.390116)
					)
				)
			)
		)
	)
	(footprint ""
		(layer "F.Cu")
		(at 92.16644 -26.152094)
		(property "Reference" "R16"
			(at -7.0866 0.162052 0)
			(unlocked yes)
			(layer "F.SilkS")
			(effects
				(font
					(size 0.7874 0.5842)
					(thickness 0.1524)
				)
				(justify left)
			)
		)
		(property "Value" ""
			(at 0 0 0)
			(layer "F.Fab")
			(effects
				(font
					(size 1.27 1.27)
				)
			)
		)
		(duplicate_pad_numbers_are_jumpers no)
		(fp_line
			(start -0.7874 -0.4064)
			(end 0.7874 -0.4064)
			(stroke
				(width 0.1524)
				(type default)
			)
			(layer "F.SilkS")
		)
		(fp_line
			(start -0.7874 0.4064)
			(end -0.7874 -0.4064)
			(stroke
				(width 0.1524)
				(type default)
			)
			(layer "F.SilkS")
		)
		(fp_line
			(start 0.7874 -0.4064)
			(end 0.7874 0.4064)
			(stroke
				(width 0.1524)
				(type default)
			)
			(layer "F.SilkS")
		)
		(fp_line
			(start 0.7874 0.4064)
			(end -0.7874 0.4064)
			(stroke
				(width 0.1524)
				(type default)
			)
			(layer "F.SilkS")
		)
		(fp_poly
			(pts
				(xy -0.508 0.2794) (xy -0.508 0.2286) (xy -0.635 0.2286) (xy -0.635 -0.254) (xy -0.5334 -0.254)
				(xy -0.5334 -0.2794) (xy 0.5334 -0.2794) (xy 0.5334 -0.254) (xy 0.635 -0.254) (xy 0.635 0.254) (xy 0.5334 0.254)
				(xy 0.5334 0.2794)
			)
			(stroke
				(width 0)
				(type default)
			)
			(fill no)
			(layer "F.CrtYd")
		)
		(pad "1" smd rect
			(at 0.40005 0)
			(size 0.4572 0.508)
			(layers "F.Cu" "F.Mask" "F.Paste")
			(net "P3V3_BLAD1")
		)
		(pad "2" smd rect
			(at -0.40005 0)
			(size 0.4572 0.508)
			(layers "F.Cu" "F.Mask" "F.Paste")
			(net "ENET10G_2_RS1")
		)
	)
	(footprint ""
		(layer "F.Cu")
		(at 325.5264 -2.6416 90)
		(property "Reference" "C28"
			(at -1.6002 -4.333748 90)
			(unlocked yes)
			(layer "F.SilkS")
			(effects
				(font
					(size 0.7874 0.5842)
					(thickness 0.1524)
				)
				(justify left)
			)
		)
		(property "Value" ""
			(at 0 0 90)
			(layer "F.Fab")
			(effects
				(font
					(size 1.27 1.27)
				)
			)
		)
		(duplicate_pad_numbers_are_jumpers no)
		(fp_line
			(start 0.7874 -0.4064)
			(end 0.7874 0.4064)
			(stroke
				(width 0.1524)
				(type default)
			)
			(layer "F.SilkS")
		)
		(fp_line
			(start -0.7874 -0.4064)
			(end 0.7874 -0.4064)
			(stroke
				(width 0.1524)
				(type default)
			)
			(layer "F.SilkS")
		)
		(fp_line
			(start 0 0.381)
			(end 0 -0.381)
			(stroke
				(width 0.1524)
				(type default)
			)
			(layer "F.SilkS")
		)
		(fp_line
			(start 0.7874 0.4064)
			(end -0.7874 0.4064)
			(stroke
				(width 0.1524)
				(type default)
			)
			(layer "F.SilkS")
		)
		(fp_line
			(start -0.7874 0.4064)
			(end -0.7874 -0.4064)
			(stroke
				(width 0.1524)
				(type default)
			)
			(layer "F.SilkS")
		)
		(fp_poly
			(pts
				(xy -0.5334 0.254) (xy -0.635 0.254) (xy -0.635 0.2286) (xy -0.635 -0.254) (xy -0.5334 -0.254) (xy -0.5334 -0.2794)
				(xy 0.5334 -0.2794) (xy 0.5334 -0.254) (xy 0.635 -0.254) (xy 0.635 0.254) (xy 0.5334 0.254) (xy 0.5334 0.2794)
				(xy -0.508 0.2794) (xy -0.5334 0.2794)
			)
			(stroke
				(width 0)
				(type default)
			)
			(fill no)
			(layer "F.CrtYd")
		)
		(pad "1" smd rect
			(at 0.40005 0 90)
			(size 0.4572 0.508)
			(layers "F.Cu" "F.Mask" "F.Paste")
			(net "P3V3_10G_4_VCCT")
		)
		(pad "2" smd rect
			(at -0.40005 0 90)
			(size 0.4572 0.508)
			(layers "F.Cu" "F.Mask" "F.Paste")
			(net "GND")
		)
	)
	(footprint ""
		(layer "F.Cu")
		(at 157.781752 -22.899878)
		(property "Reference" "R40"
			(at 33.5534 17.942052 0)
			(unlocked yes)
			(layer "F.SilkS")
			(effects
				(font
					(size 0.7874 0.5842)
					(thickness 0.1524)
				)
				(justify left)
			)
		)
		(property "Value" ""
			(at 0 0 0)
			(layer "F.Fab")
			(effects
				(font
					(size 1.27 1.27)
				)
			)
		)
		(duplicate_pad_numbers_are_jumpers no)
		(fp_line
			(start -0.7874 -0.4064)
			(end 0.7874 -0.4064)
			(stroke
				(width 0.1524)
				(type default)
			)
			(layer "F.SilkS")
		)
		(fp_line
			(start -0.7874 0.4064)
			(end -0.7874 -0.4064)
			(stroke
				(width 0.1524)
				(type default)
			)
			(layer "F.SilkS")
		)
		(fp_line
			(start 0.7874 -0.4064)
			(end 0.7874 0.4064)
			(stroke
				(width 0.1524)
				(type default)
			)
			(layer "F.SilkS")
		)
		(fp_line
			(start 0.7874 0.4064)
			(end -0.7874 0.4064)
			(stroke
				(width 0.1524)
				(type default)
			)
			(layer "F.SilkS")
		)
		(fp_poly
			(pts
				(xy -0.508 0.2794) (xy -0.508 0.2286) (xy -0.635 0.2286) (xy -0.635 -0.254) (xy -0.5334 -0.254)
				(xy -0.5334 -0.2794) (xy 0.5334 -0.2794) (xy 0.5334 -0.254) (xy 0.635 -0.254) (xy 0.635 0.254) (xy 0.5334 0.254)
				(xy 0.5334 0.2794)
			)
			(stroke
				(width 0)
				(type default)
			)
			(fill no)
			(layer "F.CrtYd")
		)
		(pad "1" smd rect
			(at 0.40005 0)
			(size 0.4572 0.508)
			(layers "F.Cu" "F.Mask" "F.Paste")
			(net "GND")
		)
		(pad "2" smd rect
			(at -0.40005 0)
			(size 0.4572 0.508)
			(layers "F.Cu" "F.Mask" "F.Paste")
			(net "ENET10G_1_TX_FAULT")
		)
	)
	(footprint ""
		(layer "F.Cu")
		(at 199.049894 -4.700016 180)
		(property "Reference" "H1"
			(at -1.899412 10.961116 0)
			(unlocked yes)
			(layer "F.SilkS")
			(effects
				(font
					(size 0.7874 0.5842)
					(thickness 0.1524)
				)
				(justify left)
			)
		)
		(property "Value" ""
			(at 0 0 180)
			(layer "F.Fab")
			(effects
				(font
					(size 1.27 1.27)
				)
			)
		)
		(duplicate_pad_numbers_are_jumpers no)
		(fp_poly
			(pts
				(arc
					(start 3.999992 5.999988)
					(mid 0 9.99998)
					(end -3.999992 5.999988)
				)
				(arc
					(start -3.999992 0)
					(mid 0 -3.999992)
					(end 3.999992 0)
				)
			)
			(stroke
				(width 0)
				(type default)
			)
			(fill no)
			(layer "B.CrtYd")
		)
		(fp_poly
			(pts
				(arc
					(start 3.999992 5.999988)
					(mid 0 9.99998)
					(end -3.999992 5.999988)
				)
				(arc
					(start -3.999992 0)
					(mid 0 -3.999992)
					(end 3.999992 0)
				)
			)
			(stroke
				(width 0)
				(type default)
			)
			(fill no)
			(layer "F.CrtYd")
		)
		(pad "" np_thru_hole circle
			(at 0 0 180)
			(size 3.5052 3.5052)
			(drill 3.5052)
			(layers "*.Cu" "*.Mask")
			(clearance 0.381)
			(thermal_gap 0.381)
		)
		(zone
			(layers "F.Cu" "B.Cu" "In1.Cu" "In2.Cu" "In3.Cu" "In4.Cu" "In5.Cu" "In6.Cu")
			(hatch none 0.5)
			(connect_pads
				(clearance 0)
			)
			(min_thickness 0.25)
			(keepout
				(tracks not_allowed)
				(vias allowed)
				(pads allowed)
				(copperpour not_allowed)
				(footprints allowed)
			)
			(placement
				(enabled no)
				(sheetname "")
			)
			(fill
				(thermal_gap 0.5)
				(thermal_bridge_width 0.5)
				(island_removal_mode 0)
			)
			(polygon
				(pts
					(arc
						(start 196.638164 -8.152638)
						(mid 199.049894 -14.207926)
						(end 201.461624 -8.152638)
					)
					(arc
						(start 201.461624 -8.152638)
						(mid 201.347995 -7.989777)
						(end 201.307954 -7.79526)
					)
					(arc
						(start 201.307954 -4.700016)
						(mid 199.049894 -2.441956)
						(end 196.791834 -4.700016)
					)
					(arc
						(start 196.791834 -7.79526)
						(mid 196.751848 -7.9898)
						(end 196.638164 -8.152638)
					)
				)
			)
		)
	)
	(footprint ""
		(layer "F.Cu")
		(at 308.3814 -33.6804 90)
		(property "Reference" "L6"
			(at -0.9398 -3.68173 90)
			(unlocked yes)
			(layer "F.SilkS")
			(effects
				(font
					(size 0.7874 0.5842)
					(thickness 0.1524)
				)
				(justify left)
			)
		)
		(property "Value" ""
			(at 0 0 90)
			(layer "F.Fab")
			(effects
				(font
					(size 1.27 1.27)
				)
			)
		)
		(duplicate_pad_numbers_are_jumpers no)
		(fp_line
			(start -1.905 -0.8636)
			(end 1.905 -0.8636)
			(stroke
				(width 0.1524)
				(type default)
			)
			(layer "F.SilkS")
		)
		(fp_line
			(start 1.905 0.8382)
			(end 1.905 -0.8382)
			(stroke
				(width 0.1524)
				(type default)
			)
			(layer "F.SilkS")
		)
		(fp_line
			(start 0.127 0.8382)
			(end 0.127 -0.8382)
			(stroke
				(width 0.1524)
				(type default)
			)
			(layer "F.SilkS")
		)
		(fp_line
			(start -0.127 0.8382)
			(end -0.127 -0.8382)
			(stroke
				(width 0.1524)
				(type default)
			)
			(layer "F.SilkS")
		)
		(fp_line
			(start -1.905 0.8382)
			(end -1.905 -0.8382)
			(stroke
				(width 0.1524)
				(type default)
			)
			(layer "F.SilkS")
		)
		(fp_line
			(start 1.905 0.8636)
			(end -1.905 0.8636)
			(stroke
				(width 0.1524)
				(type default)
			)
			(layer "F.SilkS")
		)
		(fp_rect
			(start -1.524 0.7112)
			(end 1.524 -0.7366)
			(stroke
				(width 0)
				(type default)
			)
			(fill no)
			(layer "F.CrtYd")
		)
		(pad "1" smd rect
			(at 0.94996 0 90)
			(size 1.1176 1.3716)
			(layers "F.Cu" "F.Mask" "F.Paste")
			(net "P3V3_10G_4_VCCT_L")
		)
		(pad "2" smd rect
			(at -0.94996 0 90)
			(size 1.1176 1.3716)
			(layers "F.Cu" "F.Mask" "F.Paste")
			(net "P3V3_10G_4_VCCT")
		)
	)
	(footprint ""
		(layer "F.Cu")
		(at 130.101848 -24.348694 180)
		(property "Reference" "R9"
			(at 61.753496 -5.01904 0)
			(unlocked yes)
			(layer "F.SilkS")
			(effects
				(font
					(size 0.7874 0.5842)
					(thickness 0.1524)
				)
				(justify left)
			)
		)
		(property "Value" ""
			(at 0 0 180)
			(layer "F.Fab")
			(effects
				(font
					(size 1.27 1.27)
				)
			)
		)
		(duplicate_pad_numbers_are_jumpers no)
		(fp_line
			(start 0.7874 0.4064)
			(end -0.7874 0.4064)
			(stroke
				(width 0.1524)
				(type default)
			)
			(layer "F.SilkS")
		)
		(fp_line
			(start 0.7874 -0.4064)
			(end 0.7874 0.4064)
			(stroke
				(width 0.1524)
				(type default)
			)
			(layer "F.SilkS")
		)
		(fp_line
			(start -0.7874 0.4064)
			(end -0.7874 -0.4064)
			(stroke
				(width 0.1524)
				(type default)
			)
			(layer "F.SilkS")
		)
		(fp_line
			(start -0.7874 -0.4064)
			(end 0.7874 -0.4064)
			(stroke
				(width 0.1524)
				(type default)
			)
			(layer "F.SilkS")
		)
		(fp_poly
			(pts
				(xy -0.508 0.2794) (xy -0.508 0.2286) (xy -0.635 0.2286) (xy -0.635 -0.254) (xy -0.5334 -0.254)
				(xy -0.5334 -0.2794) (xy 0.5334 -0.2794) (xy 0.5334 -0.254) (xy 0.635 -0.254) (xy 0.635 0.254) (xy 0.5334 0.254)
				(xy 0.5334 0.2794)
			)
			(stroke
				(width 0)
				(type default)
			)
			(fill no)
			(layer "F.CrtYd")
		)
		(pad "1" smd rect
			(at 0.40005 0 180)
			(size 0.4572 0.508)
			(layers "F.Cu" "F.Mask" "F.Paste")
			(net "P3V3_BLAD1")
		)
		(pad "2" smd rect
			(at -0.40005 0 180)
			(size 0.4572 0.508)
			(layers "F.Cu" "F.Mask" "F.Paste")
			(net "ENET10G_1_MOD_DEF0")
		)
	)
)
